(kicad_pcb
	(version 20241229)
	(generator "pcbnew")
	(generator_version "9.0")
	(general
		(thickness 1.62)
		(legacy_teardrops no)
	)
	(paper "A3")
	(title_block
		(title "COM Express 7 Baseboard")
		(date "2025-02-04")
		(rev "1.1.2")
		(company "Antmicro Ltd")
		(comment 1 "www.antmicro.com")
		(comment 9 "footprints 243-243 of 802")
	)
	(layers
		(0 "F.Cu" signal)
		(4 "In1.Cu" signal)
		(6 "In2.Cu" signal)
		(8 "In3.Cu" signal)
		(10 "In4.Cu" signal)
		(12 "In5.Cu" signal)
		(14 "In6.Cu" signal)
		(2 "B.Cu" signal)
		(9 "F.Adhes" user "F.Adhesive")
		(11 "B.Adhes" user "B.Adhesive")
		(13 "F.Paste" user)
		(15 "B.Paste" user)
		(5 "F.SilkS" user "F.Silkscreen")
		(7 "B.SilkS" user "B.Silkscreen")
		(1 "F.Mask" user)
		(3 "B.Mask" user)
		(17 "Dwgs.User" user "User.Drawings")
		(19 "Cmts.User" user "User.Comments")
		(21 "Eco1.User" user "User.Eco1")
		(23 "Eco2.User" user "User.Eco2")
		(25 "Edge.Cuts" user)
		(27 "Margin" user)
		(31 "F.CrtYd" user "F.Courtyard")
		(29 "B.CrtYd" user "B.Courtyard")
		(35 "F.Fab" user)
		(33 "B.Fab" user)
	)
	(footprint "antmicro-footprints:R_0402_1005Metric"
		(layer "F.Cu")
		(at 192.342893 129.492893 -135)
		(descr "Resistor SMD 0402")
		(tags "resistor SMD 0402")
		(property "Reference" "R219"
			(at -3.65 -0.4 45)
			(layer "F.SilkS")
			(effects
				(font
					(size 0.7 0.7)
					(thickness 0.15)
				)
				(justify right bottom)
			)
		)
		(property "Value" "R_1k_0402"
			(at -1.011843 1.772046 45)
			(layer "F.Fab")
			(effects
				(font
					(size 0.7 0.7)
					(thickness 0.15)
				)
				(justify right bottom)
			)
		)
		(property "Datasheet" "https://www.bourns.com/docs/product-datasheets/cr.pdf"
			(at 0 0 45)
			(layer "F.Fab")
			(hide yes)
			(effects
				(font
					(size 1.27 1.27)
					(thickness 0.15)
				)
			)
		)
		(property "Author" "Antmicro"
			(at 389.1 261.22 45)
			(layer "F.Fab")
			(hide yes)
			(effects
				(font
					(size 1 1)
					(thickness 0.15)
				)
			)
		)
		(property "License" "Apache-2.0"
			(at 389.1 261.22 45)
			(layer "F.Fab")
			(hide yes)
			(effects
				(font
					(size 1 1)
					(thickness 0.15)
				)
			)
		)
		(property "MPN" "CR0402-FX-1001GLF"
			(at 389.1 261.22 45)
			(layer "F.Fab")
			(hide yes)
			(effects
				(font
					(size 1 1)
					(thickness 0.15)
				)
			)
		)
		(property "Manufacturer" "Bourns"
			(at 389.1 261.22 45)
			(layer "F.Fab")
			(hide yes)
			(effects
				(font
					(size 1 1)
					(thickness 0.15)
				)
			)
		)
		(property "Public" "False"
			(at 389.1 261.22 45)
			(layer "F.Fab")
			(hide yes)
			(effects
				(font
					(size 1 1)
					(thickness 0.15)
				)
			)
		)
		(property "Tolerance" "1%"
			(at 389.1 261.22 45)
			(layer "F.Fab")
			(hide yes)
			(effects
				(font
					(size 1 1)
					(thickness 0.15)
				)
			)
		)
		(property "Val" "1k"
			(at 389.1 261.22 45)
			(layer "F.Fab")
			(hide yes)
			(effects
				(font
					(size 1 1)
					(thickness 0.15)
				)
			)
		)
		(sheetname "PCIe redriver")
		(sheetfile "pcie_redriver.kicad_sch")
		(attr smd)
		(fp_poly
			(pts
				(xy -0.925 -0.47) (xy 0.925 -0.47) (xy 0.925 0.47) (xy -0.925 0.47)
			)
			(stroke
				(width 0.05)
				(type default)
			)
			(fill no)
			(layer "F.CrtYd")
		)
		(fp_poly
			(pts
				(xy -0.5 -0.25) (xy 0.5 -0.25) (xy 0.5 0.25) (xy -0.5 0.25)
			)
			(stroke
				(width 0.15)
				(type solid)
			)
			(fill no)
			(layer "F.Fab")
		)
		(pad "1" smd roundrect
			(at -0.48 0 225)
			(size 0.59 0.64)
			(layers "F.Cu" "F.Mask" "F.Paste")
			(roundrect_rratio 0.25)
			(net 2 "+3V3")
			(pintype "passive")
			(teardrops
				(best_length_ratio 0.2)
				(max_length 1)
				(best_width_ratio 0.9)
				(max_width 2)
				(curved_edges yes)
				(filter_ratio 0.9)
				(enabled yes)
				(allow_two_segments yes)
				(prefer_zone_connections yes)
			)
		)
		(pad "2" smd roundrect
			(at 0.48 0 225)
			(size 0.59 0.64)
			(layers "F.Cu" "F.Mask" "F.Paste")
			(roundrect_rratio 0.25)
			(net 973 "/PCIe redriver/RX_SW")
			(pintype "passive")
			(teardrops
				(best_length_ratio 0.2)
				(max_length 1)
				(best_width_ratio 0.9)
				(max_width 2)
				(curved_edges yes)
				(filter_ratio 0.9)
				(enabled yes)
				(allow_two_segments yes)
				(prefer_zone_connections yes)
			)
		)
	)
)
